# T6G (Grand Teton) — schematic parts with pin connectivity, parts 4886–5033 of 8303; source: Cadence DE-HDL packaged netlist (pstxprt.dat, pstxnet.dat, pstchip.dat)

R162  Q_RES  0 5% CHIP  pkg 0402LF  page 160 : 1 = SMB_CPU0_CPU1_APML_SDA ; 2 = SMB_CPU0_CPU1_APML_BUF2_SDA
R163  Q_RES  33 5% CHIP  pkg 0402LF  page 80 : 1 = FM_I3C_CPU0_MUX0_OE_R_N ; 2 = FM_I3C_CPU0_MUX0_OE_N
R164  Q_RES  33 5% CHIP  pkg 0402LF  page 80 : 1 = FM_I3C_CPU0_MUX0_R_SEL ; 2 = FM_I3C_CPU0_MUX0_SEL
R165  Q_RES  33 5% CHIP  pkg 0402LF  page 80 : 1 = FM_I3C_CPU0_MUX1_OE_R_N ; 2 = FM_I3C_CPU0_MUX1_OE_N
R166  Q_RES  33 5% CHIP  pkg 0402LF  page 80 : 1 = FM_I3C_CPU0_MUX1_R_SEL ; 2 = FM_I3C_CPU0_MUX1_SEL
R167  Q_RES  0 5% CHIP  pkg 0402LF  page 80 : 1 = SGPIO_SCM_DI_R<0> ; 2 = SGPIO_SCM_DI_<0>
R168  Q_RES  0 5% CHIP  pkg 0402LF  page 80 : 1 = SGPIO_SCM_DI_R<1> ; 2 = SGPIO_SCM_DI_<1>
R169  Q_RES  33 5% CHIP  pkg 0402LF  page 80 : 1 = FM_I3C_CPU1_MUX0_OE_R_N ; 2 = FM_I3C_CPU1_MUX0_OE_N
R170  Q_RES  33 5% CHIP  pkg 0402LF  page 80 : 1 = FM_I3C_CPU1_MUX0_R_SEL ; 2 = FM_I3C_CPU1_MUX0_SEL
R171  Q_RES  33 5% CHIP  pkg 0402LF  page 80 : 1 = FM_I3C_CPU1_MUX1_OE_R_N ; 2 = FM_I3C_CPU1_MUX1_OE_N
R172  Q_RES  33 5% CHIP  pkg 0402LF  page 80 : 1 = FM_I3C_CPU1_MUX1_R_SEL ; 2 = FM_I3C_CPU1_MUX1_SEL
R173  Q_RES  33 5% CHIP  pkg 0402LF  page 81 : 1 = FM_PLD_CPU1_PRSNT_HDT ; 2 = CPU1_HDT_BYPASS_SEL
R174  Q_RES  33 5% CHIP  pkg 0402LF  page 81 : 1 = SCM_IRQ_1V8_R_N ; 2 = SCM_IRQ_1V8_N
R175  Q_RES  0 5% CHIP  pkg 0402LF  page 210 : 1 = SMB_VR_3V3STBY_SCL ; 2 = PVDDCR_CPU0_P1_PMSCL_R
R176  Q_RES  33 5% CHIP  pkg 0402LF  page 81 : 1 = PVDD18_S5_P0_EN ; 2 = FM_PVDD18_S5_P0_EN
R177  Q_RES  33 5% CHIP  pkg 0402LF  page 209 : 1 = PWRGD_PVDD18_S5_P0 ; 2 = FM_PWRGD_PVDD18_S5_P0
R178  Q_RES  1K 1% CHIP  pkg 0402LF  page 144 : 1 = P3V3_AUX ; 2 = PCIE_M2_SSD0_PRSNT_N
R179  Q_RES  33 5% CHIP  pkg 0402LF  page 82 : 1 = FM_CPU0_PROCHOT_R_N ; 2 = CPU0_PROCHOT_N
R180  Q_RES  0 5% CHIP  pkg 0402LF  page 82 : 1 = CPU0_SP5R1 ; 2 = FM_CPU0_SP5R1
R181  Q_RES  0 5% CHIP  pkg 0402LF  page 82 : 1 = CPU0_SP5R2 ; 2 = FM_CPU0_SP5R2
R182  Q_RES  0 5% CHIP  pkg 0402LF  page 82 : 1 = FM_PRSNT_CPU0_R_N ; 2 = FM_PRSNT_CPU0_N
R183  Q_RES  0 5% CHIP  pkg 0402LF  page 82 : 1 = CPU0_CORETYPE0 ; 2 = FM_CPU0_CORETYPE0
R184  Q_RES  0 5% CHIP  pkg 0402LF  page 82 : 1 = CPU0_CORETYPE1 ; 2 = FM_CPU0_CORETYPE1
R185  Q_RES  0 5% CHIP  pkg 0402LF  page 82 : 1 = CPU0_CORETYPE2 ; 2 = FM_CPU0_CORETYPE2
R186  Q_RES  33 5% CHIP  pkg 0402LF  page 81 : 1 = FM_CPU0_FORCE_SELFREFRESH ; 2 = CPU0_FORCE_SELFREFRESH
R187  Q_RES  0 5% CHIP  pkg 0402LF  page 82 : 1 = IRQ_CPU_BMC_NMI_N ; 2 = IRQ_CPU_BMC_NMI_R_N
R188  Q_RES  0 5% CHIP  pkg 0402LF  page 82 : 1 = FM_BMC_READY_N ; 2 = FM_BMC_READY_R_N
R189  Q_RES  0 5% CHIP  pkg 0402LF  page 82 : 1 = FM_BMC_TPM_PRES_N ; 2 = FM_BMC_TPM_PRES_N_R
R190  Q_RES  0 5% CHIP  pkg 0402LF  page 82 : 1 = FM_CPU1_BMC_RST_N ; 2 = FM_CPU1_BMC_RST_R_N
R191  Q_RES  0 5% EMPTY  pkg 0402LF  page 55 : 1 = FM_CPU1_SLP_S5_N ; 2 = CPU1_SLP_S5_N
R192  Q_RES  0 5% EMPTY  pkg 0402LF  page 55 : 1 = FM_CPU1_SLP_S3_N ; 2 = CPU1_SLP_S3_N
R193  Q_RES  0 5% CHIP  pkg 0402LF  page 81 : 1 = FM_CPU1_SMERR_N ; 2 = CPU1_SMERR_N
R194  Q_RES  0 5% CHIP  pkg 0402LF  page 81 : 1 = CPU1_SPD_HOST_CTRL_N ; 2 = CPU1_SPD_HOST_CTRL_R1_N
R195  Q_RES  33 5% CHIP  pkg 0402LF  page 81 : 1 = FM_CPU1_PWRGD_OUT ; 2 = CPU1_PWRGD_OUT
R196  Q_RES  0 5% CHIP  pkg 0402LF  page 81 : 1 = CPU1_NV_SAVE_N ; 2 = FM_CPU1_NV_SAVE_N
R197  Q_RES  0 5% CHIP  pkg 0402LF  page 81 : 1 = RST_CPU1_PERST0_N ; 2 = RST_CPU1_PERST0_R_N
R198  Q_RES  0 5% CHIP  pkg 0402LF  page 81 : 1 = RST_CPU1_PERST1_N ; 2 = RST_CPU1_PERST1_R_N
R199  Q_RES  33 5% CHIP  pkg 0402LF  page 81 : 1 = E1S_0_P12V_EN ; 2 = P12V_E1S_0_EN
R200  Q_RES  4.7K 5% EMPTY  pkg 0402LF  page 160 : 1 = P3V3_AUX ; 2 = PU_U96_EN
R201  Q_RES  4.7K 5% EMPTY  pkg 0402LF  page 160 : 1 = P3V3_AUX ; 2 = PU_U2_EN
R202  Q_RES  0 5% CHIP  pkg 0402LF  page 160 : 1 = SMB_CPU0_CPU1_APML_BUF2_SCL_R1 ; 2 = SMB_CPU0_CPU1_APML_BUF2_SCL_R2
R203  Q_RES  0 5% CHIP  pkg 0402LF  page 81 : 1 = PWRGD_CPU1_PWROK ; 2 = FM_PWRGD_CPU1_PWROK
R204  Q_RES  0 5% CHIP  pkg 0402LF  page 82 : 1 = CPU1_XTRIG_L4 ; 2 = FM_CPU1_XTRIG_L4
R205  Q_RES  0 5% CHIP  pkg 0402LF  page 82 : 1 = CPU1_XTRIG_L5 ; 2 = FM_CPU1_XTRIG_L5
R206  Q_RES  0 5% CHIP  pkg 0402LF  page 160 : 1 = SMB_CPU0_CPU1_APML_BUF2_SDA_R1 ; 2 = SMB_CPU0_CPU1_APML_BUF2_SDA_R2
R207  Q_RES  2.2K 5% CHIP  pkg 0402LF  page 28 : 1 = FM_INT_CPU0_HP_UBM_N ; 2 = PVDD18_S5_P0
R208  Q_RES  33 5% CHIP  pkg 0402LF  page 81 : 1 = PVDDCR_CPU0_P1_EN ; 2 = FM_PVDDCR_CPU0_P1_R_EN
R209  Q_RES  0 5% CHIP  pkg 0402LF  page 81 : 1 = PWRGD_PVDDCR_CPU0_P1 ; 2 = FM_PWRGD_PVDDCR_CPU0_P1
R210  Q_RES  0 5% CHIP  pkg 0402LF  page 80 : 1 = SMB_2_PLD_3V3AUX_SCL_R1 ; 2 = SMB_2_PLD_3V3AUX_SCL_R2
R211  Q_RES  0 5% CHIP  pkg 0402LF  page 80 : 1 = SMB_2_PLD_3V3AUX_SDA_R1 ; 2 = SMB_2_PLD_3V3AUX_SDA_R2
R212  Q_RES  33 5% CHIP  pkg 0402LF  page 28 : 1 = SMB_CPU_5_R_SCL ; 2 = SMB_CPU_5_SCL
R213  Q_RES  0 5% CHIP  pkg 0402LF  page 28 : 1 = SMB_CPU_5_R_SDA ; 2 = SMB_CPU_5_SDA
R214  Q_RES  33 5% CHIP  pkg 0402LF  page 269 : 1 = PWRGD_P1V8_AUX ; 2 = PWRGD_P1V8_AUX_R
R215  Q_RES  33 5% CHIP  pkg 0402LF  page 81 : 1 = CPU0_PWR_BTN_N ; 2 = FM_CPU0_PWR_BTN_N
R216  Q_RES  33 5% CHIP  pkg 0402LF  page 81 : 1 = RST_CPU0_SYS_N ; 2 = FM_CPU0_SYS_RESET_N
R217  Q_RES  33 5% CHIP  pkg 0402LF  page 81 : 1 = RST_CPU0_RSMRST_N ; 2 = FM_CPU0_RSMRST_N
R218  Q_RES  33 5% CHIP  pkg 0402LF  page 81 : 1 = CPU0_PWR_GOOD ; 2 = FM_CPU0_PWR_GOOD
R219  Q_RES  33 5% CHIP  pkg 0402LF  page 81 : 1 = CPU0_NMI_SYNC_FLOOD_N ; 2 = FM_CPU0_NMI_SYNC_FLOOD_N
R220  Q_RES  33 5% CHIP  pkg 0402LF  page 82 : 1 = FM_CPU0_SA0 ; 2 = CPU0_SA0
R221  Q_RES  33 5% CHIP  pkg 0402LF  page 82 : 1 = FM_CPU0_SA1 ; 2 = CPU0_SA1
R222  Q_RES  0 5% CHIP  pkg 0402LF  page 82 : 1 = CPU0_SP5R3 ; 2 = FM_CPU0_SP5R3
R223  Q_RES  0 5% CHIP  pkg 0402LF  page 82 : 1 = FM_CPU0_SP5R4 ; 2 = CPU0_SP5R4
R224  Q_RES  33 5% CHIP  pkg 0402LF  page 81 : 1 = PVDD33_S5_EN ; 2 = FM_PVDD33_S5_EN
R225  Q_RES  33 5% CHIP  pkg 0402LF  page 192 : 1 = PWRGD_PVDD33_S5 ; 2 = FM_PWRGD_PVDD33_S5
R226  Q_RES  0 5% CHIP  pkg 0402LF  page 82 : 1 = FM_PVDD11_S3_P0_OCP_N ; 2 = PVDD11_S3_P0_OCP_N
R227  Q_RES  33 5% CHIP  pkg 0402LF  page 82 : 1 = FM_PVDD11_S3_P0_EN ; 2 = PVDD11_S3_P0_EN
R228  Q_RES  0 5% CHIP  pkg 0402LF  page 81 : 1 = PWRGD_PVDD11_S3_P0 ; 2 = FM_PWRGD_PVDD11_S3_P0
R229  Q_RES  33 5% CHIP  pkg 0402LF  page 81 : 1 = PVDDIO_P0_EN ; 2 = FM_PVDDIO_P0_EN
R230  Q_RES  0 5% CHIP  pkg 0402LF  page 81 : 1 = PWRGD_PVDDIO_P0 ; 2 = FM_PWRGD_PVDDIO_P0
R231  Q_RES  0 5% CHIP  pkg 0402LF  page 82 : 1 = PVDDCR_CPU0_P0_OCP_N ; 2 = FM_PVDDCR_CPU0_P0_OCP_N
R232  Q_RES  33 5% CHIP  pkg 0402LF  page 82 : 1 = FM_PVDDCR_CPU1_P0_EN ; 2 = FM_PVDDCR_CPU1_P0_R_EN
R233  Q_RES  0 5% CHIP  pkg 0402LF  page 82 : 1 = PWRGD_PVDDCR_CPU1_P0 ; 2 = FM_PWRGD_PVDDCR_CPU1_P0
R234  Q_RES  0 5% CHIP  pkg 0402LF  page 82 : 1 = CPU1_XTRIG_L6 ; 2 = FM_CPU1_XTRIG_L6
R235  Q_RES  0 5% CHIP  pkg 0402LF  page 82 : 1 = CPU1_XTRIG_L7 ; 2 = FM_CPU1_XTRIG_L7
R236  Q_RES  0 5% CHIP  pkg 0402LF  page 82 : 1 = CPU0_XTRIG_L4 ; 2 = FM_CPU0_XTRIG_L4
R237  Q_RES  0 5% CHIP  pkg 0402LF  page 82 : 1 = CPU0_XTRIG_L5 ; 2 = FM_CPU0_XTRIG_L5
R238  Q_RES  0 5% CHIP  pkg 0402LF  page 82 : 1 = CPU0_XTRIG_L6 ; 2 = FM_CPU0_XTRIG_L6
R239  Q_RES  0 5% CHIP  pkg 0402LF  page 82 : 1 = CPU0_XTRIG_L7 ; 2 = FM_CPU0_XTRIG_L7
R240  Q_RES  100 1% CHIP  pkg 0402LF  page 217 : 1 = PVDDCR_CPU1_P1_RESET_N ; 2 = PVDDCR_CPU1_P1_RESET_N_R
R241  Q_RES  0 5% CHIP  pkg 0402LF  page 81 : 1 = RST_CPU0_RESETL_N ; 2 = FM_RST_CPU0_RESETL_N
R242  Q_RES  0 5% CHIP  pkg 0402LF  page 81 : 1 = PWRGD_CPU0_PWROK ; 2 = FM_PWRGD_CPU0_PWROK
R243  Q_RES  0 5% CHIP  pkg 0402LF  page 82 : 1 = FM_SMM_CRASHDUMP ; 2 = FM_SMM_CRASHDUMP_R
R244  Q_RES  0 5% CHIP  pkg 0402LF  page 82 : 1 = IRQ_BMC_SMI_N ; 2 = IRQ_BMC_SMI_R_N
R245  Q_RES  0 5% CHIP  pkg 0402LF  page 82 : 1 = IRQ_SMI_ACTIVE_N ; 2 = IRQ_SMI_ACTIVE_N_R
R246  Q_RES  0 5% CHIP  pkg 0402LF  page 82 : 1 = IRQ_TPM_SPI_R_N ; 2 = IRQ_TPM_SPI_R1_N
R247  Q_RES  33 5% CHIP  pkg 0402LF  page 27 : 1 = APML_CPU0_ALERT_N ; 2 = APML_CPU0_ALERT_R_N
R248  Q_RES  33 5% CHIP  pkg 0402LF  page 28 : 1 = FM_CPU0_SLP_S5_N ; 2 = CPU0_SLP_S5_N
R249  Q_RES  33 5% CHIP  pkg 0402LF  page 28 : 1 = FM_CPU0_SLP_S3_N ; 2 = CPU0_SLP_S3_N
R250  Q_RES  0 5% CHIP  pkg 0402LF  page 81 : 1 = FM_CPU0_SMERR_N ; 2 = CPU0_SMERR_N
R251  Q_RES  0 5% CHIP  pkg 0402LF  page 81 : 1 = CPU0_SPD_HOST_CTRL_R1_N ; 2 = CPU0_SPD_HOST_CTRL_N
R252  Q_RES  0 5% CHIP  pkg 0402LF  page 81 : 1 = FM_CPU1_PWR_GD_IN ; 2 = CPU1_PWR_GD_IN
R253  Q_RES  0 5% CHIP  pkg 0402LF  page 81 : 1 = CPU0_NV_SAVE_N ; 2 = FM_CPU0_NV_SAVE_N
R254  Q_RES  0 5% CHIP  pkg 0402LF  page 81 : 1 = RST_CPU0_PERST0_N ; 2 = RST_CPU0_PERST0_R_N
R255  Q_RES  0 5% CHIP  pkg 0402LF  page 81 : 1 = RST_CPU0_PERST1_N ; 2 = RST_CPU0_PERST1_R_N
R256  Q_RES  0 5% EMPTY  pkg 0402LF  page 160 : 1 = SMB_CPU0_CPU1_APML_BUF1_SCL_R2 ; 2 = SMB_CPU0_CPU1_APML_SCL_R2
R257  Q_RES  0 5% EMPTY  pkg 0402LF  page 160 : 1 = SMB_CPU0_CPU1_APML_BUF1_SDA_R2 ; 2 = SMB_CPU0_CPU1_APML_SDA_R2
R258  Q_RES  0 5% CHIP  pkg 0402LF  page 81 : 1 = FM_CPU0_HDT_CONN_TESTEN ; 2 = CPU0_HDT_CONN_TESTEN
R259  Q_RES  33 5% CHIP  pkg 0402LF  page 226 : 1 = PWRGD_PVDD18_S5_P1 ; 2 = PWRGD_PVDD18_S5_R_P1
R260  Q_RES  0 5% CHIP  pkg 0402LF  page 82 : 1 = CPU1_SP5R1 ; 2 = FM_CPU1_SP5R1
R261  Q_RES  0 5% CHIP  pkg 0402LF  page 82 : 1 = CPU1_SP5R2 ; 2 = FM_CPU1_SP5R2
R262  Q_RES  0 5% CHIP  pkg 0402LF  page 82 : 1 = CPU1_CORETYPE0 ; 2 = FM_CPU1_CORETYPE0
R263  Q_RES  0 5% CHIP  pkg 0402LF  page 82 : 1 = CPU1_CORETYPE1 ; 2 = FM_CPU1_CORETYPE1
R264  Q_RES  0 5% CHIP  pkg 0402LF  page 82 : 1 = CPU1_CORETYPE2 ; 2 = FM_CPU1_CORETYPE2
R265  Q_RES  33 5% CHIP  pkg 0402LF  page 81 : 1 = FM_CPU1_FORCE_SELFREFRESH ; 2 = CPU1_FORCE_SELFREFRESH
R266  Q_RES  33 5% CHIP  pkg 0402LF  page 82 : 1 = FM_CPU1_SA0 ; 2 = CPU1_SA0
R267  Q_RES  33 5% CHIP  pkg 0402LF  page 82 : 1 = CPU1_SA1 ; 2 = FM_CPU1_SA1
R268  Q_RES  0 5% CHIP  pkg 0402LF  page 82 : 1 = CPU1_SP5R3 ; 2 = FM_CPU1_SP5R3
R269  Q_RES  0 5% CHIP  pkg 0402LF  page 82 : 1 = CPU1_SP5R4 ; 2 = FM_CPU1_SP5R4
R270  Q_RES  33 5% CHIP  pkg 0402LF  page 82 : 1 = FM_CPU1_PROCHOT_R_N ; 2 = CPU1_PROCHOT_N
R271  Q_RES  0 5% CHIP  pkg 0402LF  page 82 : 1 = FM_PRSNT_CPU1_R_N ; 2 = FM_PRSNT_CPU1_N
R272  Q_RES  0 5% EMPTY  pkg 0402LF  page 81 : 1 = RST_CPU1_SYS_N ; 2 = FM_CPU1_SYS_RESET_N
R273  Q_RES  33 5% CHIP  pkg 0402LF  page 81 : 1 = RST_CPU1_RSMRST_N ; 2 = FM_CPU1_RSMRST_N
R274  Q_RES  0 5% CHIP  pkg 0402LF  page 160 : 1 = SMB_CPU0_CPU1_APML_BUF2_SCL_R2 ; 2 = SMB_CPU0_CPU1_APML_SCL_R2
R275  Q_RES  33 5% CHIP  pkg 0402LF  page 82 : 1 = CLR_CMOS ; 2 = FM_CLR_CMOS
R276  Q_RES  4.7K 5% CHIP  pkg 0402LF  page 28 : 1 = CPU0_PWR_GOOD ; 2 = PVDD18_S5_P0
R277  Q_RES  33 5% CHIP  pkg 0402LF  page 81 : 1 = FM_CPU1_NMI_SYNC_FLOOD_N ; 2 = CPU1_NMI_SYNC_FLOOD_N
R278  Q_RES  0 5% CHIP  pkg 0402LF  page 82 : 1 = FM_PVDD11_S3_P1_OCP_N ; 2 = PVDD11_S3_P1_OCP_N
R279  Q_RES  33 5% CHIP  pkg 0402LF  page 81 : 1 = PVDD11_S3_P1_EN ; 2 = FM_PVDD11_S3_P1_EN
R280  Q_RES  0 5% CHIP  pkg 0402LF  page 81 : 1 = PWRGD_PVDD11_S3_P1 ; 2 = FM_PWRGD_PVDD11_S3_P1
R281  Q_RES  0 5% CHIP  pkg 0402LF  page 160 : 1 = SMB_CPU0_CPU1_APML_BUF2_SDA_R2 ; 2 = SMB_CPU0_CPU1_APML_SDA_R2
R282  Q_RES  33 5% CHIP  pkg 0402LF  page 81 : 1 = PVDDIO_P1_EN ; 2 = FM_PVDDIO_P1_EN
R283  Q_RES  0 5% CHIP  pkg 0402LF  page 81 : 1 = PWRGD_PVDDIO_P1 ; 2 = FM_PWRGD_PVDDIO_P1
R284  Q_RES  0 5% CHIP  pkg 0402LF  page 82 : 1 = FM_PVDDCR_CPU0_P1_OCP_N ; 2 = PVDDCR_CPU0_P1_OCP_N
R285  Q_RES  33 5% CHIP  pkg 0402LF  page 82 : 1 = FM_PVDDCR_CPU1_P1_R_EN ; 2 = FM_PVDDCR_CPU1_P1_EN
R286  Q_RES  0 5% CHIP  pkg 0402LF  page 81 : 1 = PWRGD_PVDDCR_CPU1_P1 ; 2 = FM_PWRGD_PVDDCR_CPU1_P1
R287  Q_RES  4.7K 5% EMPTY  pkg 0402LF  page 28 : 1 = GND ; 2 = CPU0_PWR_GOOD
R288  Q_RES  4.7K 5% EMPTY  pkg 0402LF  page 28 : 1 = CPU0_PWR_GD_OUT ; 2 = PVDD18_S5_P0
R289  Q_RES  33 5% CHIP  pkg 0402LF  page 81 : 1 = PVDD18_S5_P1_EN ; 2 = PVDD18_S5_P1_R_EN
R290  Q_RES  1K 1% EMPTY  pkg 0402LF  page 160 : 1 = PVDD11_S3_P0 ; 2 = SMB_CPU0_CPU1_APML_BUF2_SDA_R2
R291  Q_RES  1K 1% CHIP  pkg 0402LF  page 86 : 1 = PWRGD_CHA_CPU0_DIMM0 ; 2 = PWRGD_CHAF_CPU0
R292  Q_RES  1K 1% CHIP  pkg 0402LF  page 87 : 1 = PWRGD_CHB_CPU0_DIMM ; 2 = PWRGD_CHAF_CPU0
R293  Q_RES  1K 1% CHIP  pkg 0402LF  page 88 : 1 = PWRGD_CHC_CPU0_DIMM ; 2 = PWRGD_CHAF_CPU0
R294  Q_RES  1K 1% CHIP  pkg 0402LF  page 89 : 1 = PWRGD_CHD_CPU0_DIMM ; 2 = PWRGD_CHAF_CPU0
R295  Q_RES  1K 1% CHIP  pkg 0402LF  page 90 : 1 = PWRGD_CHE_CPU0_DIMM ; 2 = PWRGD_CHAF_CPU0
R296  Q_RES  1K 1% CHIP  pkg 0402LF  page 91 : 1 = PWRGD_CHF_CPU0_DIMM ; 2 = PWRGD_CHAF_CPU0
R297  Q_RES  1K 1% CHIP  pkg 0402LF  page 92 : 1 = PWRGD_CHG_CPU0_DIMM0 ; 2 = PWRGD_CHGL_CPU0
R298  Q_RES  1K 1% CHIP  pkg 0402LF  page 93 : 1 = PWRGD_CHH_CPU0_DIMM ; 2 = PWRGD_CHGL_CPU0
R299  Q_RES  1K 1% CHIP  pkg 0402LF  page 94 : 1 = PWRGD_CHI_CPU0_DIMM ; 2 = PWRGD_CHGL_CPU0
R300  Q_RES  1K 1% CHIP  pkg 0402LF  page 95 : 1 = PWRGD_CHJ_CPU0_DIMM ; 2 = PWRGD_CHGL_CPU0
R301  Q_RES  1K 1% CHIP  pkg 0402LF  page 96 : 1 = PWRGD_CHK_CPU0_DIMM ; 2 = PWRGD_CHGL_CPU0
R302  Q_RES  1K 1% CHIP  pkg 0402LF  page 97 : 1 = PWRGD_CHL_CPU0_DIMM ; 2 = PWRGD_CHGL_CPU0
R303  Q_RES  1K 1% CHIP  pkg 0402LF  page 98 : 1 = PWRGD_CHA_CPU1_DIMM0 ; 2 = PWRGD_CHAF_CPU1
R304  Q_RES  1K 1% CHIP  pkg 0402LF  page 99 : 1 = PWRGD_CHB_CPU1_DIMM ; 2 = PWRGD_CHAF_CPU1
R305  Q_RES  1K 1% CHIP  pkg 0402LF  page 100 : 1 = PWRGD_CHC_CPU1_DIMM ; 2 = PWRGD_CHAF_CPU1
R306  Q_RES  1K 1% CHIP  pkg 0402LF  page 101 : 1 = PWRGD_CHD_CPU1_DIMM ; 2 = PWRGD_CHAF_CPU1
R307  Q_RES  1K 1% CHIP  pkg 0402LF  page 102 : 1 = PWRGD_CHE_CPU1_DIMM ; 2 = PWRGD_CHAF_CPU1
R308  Q_RES  33 5% CHIP  pkg 0402LF  page 151 : 1 = SMB_VR_3V3AUX_SCL ; 2 = SMB_VR_3V3STBY_SCL
R309  Q_RES  33 5% CHIP  pkg 0402LF  page 151 : 1 = SMB_VR_3V3AUX_SDA ; 2 = SMB_VR_3V3STBY_SDA
